# T6G (Grand Teton) — schematic netlist excerpt (pin names and nets, part order shuffled) for the footprints in the layout excerpt that follows; sources: Cadence DE-HDL packaged netlist, KiCad conversion of 04192023_DAF0TMB3IC0_F0TG_MB_C_brd_V02_OCP.brd

PR3829  Q_RES  7.15K 1% CHIP  pkg 0402LF  page 140 : A = P3V3_OCP_UV_2 ; B = P3V3_OCP_OV_2
C6016  Q_CAP_DIFFBUS  DIFF BUS_0.33UF 6.3V 10% X6S  pkg C0402  page 180 : \1\ = USB3_CPU0_BMC_RX_HUB1_DN ; \2\ = USB3_CPU0_BMC_RX_HUB_C_DN

(kicad_pcb
	(version 20260206)
	(generator "pcbnew")
	(generator_version "10.0")
	(general
		(thickness 1.6)
		(legacy_teardrops no)
	)
	(paper "A4")
	(title_block
		(title "04192023_DAF0TMB3IC0_F0TG_MB_C_brd_V02_OCP.brd")
		(comment 1 "Grand Teton / footprints 4891-4892 of 8354")
	)
	(layers
		(0 "F.Cu" signal "TOP")
		(4 "In1.Cu" signal "GND")
		(6 "In2.Cu" signal "IN1")
		(8 "In3.Cu" signal "GND1")
		(10 "In4.Cu" signal "IN2")
		(12 "In5.Cu" signal "GND2")
		(14 "In6.Cu" signal "IN3")
		(16 "In7.Cu" signal "GND3")
		(18 "In8.Cu" signal "VCC")
		(20 "In9.Cu" signal "VCC1")
		(22 "In10.Cu" signal "GND4")
		(24 "In11.Cu" signal "IN4")
		(26 "In12.Cu" signal "GND5")
		(28 "In13.Cu" signal "IN5")
		(30 "In14.Cu" signal "GND6")
		(32 "In15.Cu" signal "IN6")
		(34 "In16.Cu" signal "GND7")
		(2 "B.Cu" signal "BOTTOM")
		(9 "F.Adhes" user "F.Adhesive")
		(11 "B.Adhes" user "B.Adhesive")
		(13 "F.Paste" user "Package Geometry/Pastemask Top")
		(15 "B.Paste" user "Package Geometry/Pastemask Bottom")
		(5 "F.SilkS" user "Ref Des/Silkscreen Top")
		(7 "B.SilkS" user "Ref Des/Silkscreen Bottom")
		(1 "F.Mask" user "Board Geometry/Soldermask Top")
		(3 "B.Mask" user "Board Geometry/Soldermask Bottom")
		(17 "Dwgs.User" user "User.Drawings")
		(19 "Cmts.User" user "User.Comments")
		(21 "Eco1.User" user "User.Eco1")
		(23 "Eco2.User" user "User.Eco2")
		(25 "Edge.Cuts" user "Board Geometry/Outline")
		(27 "Margin" user)
		(31 "F.CrtYd" user "Package Geometry/Place Bound Top")
		(29 "B.CrtYd" user "Package Geometry/Place Bound Bottom")
		(35 "F.Fab" user "Ref Des/Assembly Top")
		(33 "B.Fab" user "Ref Des/Assembly Bottom")
	)
	(footprint ""
		(layer "F.Cu")
		(at 140.02512 -31.62681 -90)
		(property "Reference" "C6016"
			(at 0 0 270)
			(layer "F.SilkS")
			(hide yes)
			(effects
				(font
					(size 1.27 1.27)
				)
			)
		)
		(property "Value" ""
			(at 0 0 270)
			(layer "F.Fab")
			(effects
				(font
					(size 1.27 1.27)
				)
			)
		)
		(duplicate_pad_numbers_are_jumpers no)
		(fp_line
			(start 0.40005 0.4064)
			(end -0.40005 0.4064)
			(stroke
				(width 0.1524)
				(type default)
			)
			(layer "F.SilkS")
		)
		(fp_line
			(start -0.6858 0.3048)
			(end -0.6858 -0.3048)
			(stroke
				(width 0.1)
				(type default)
			)
			(layer "F.Fab")
		)
		(fp_line
			(start -0.1016 0.3048)
			(end -0.6858 0.3048)
			(stroke
				(width 0.1)
				(type default)
			)
			(layer "F.Fab")
		)
		(fp_line
			(start 0.1016 0.3048)
			(end 0.1016 0.2794)
			(stroke
				(width 0.1)
				(type default)
			)
			(layer "F.Fab")
		)
		(fp_line
			(start 0.6858 0.3048)
			(end 0.1016 0.3048)
			(stroke
				(width 0.1)
				(type default)
			)
			(layer "F.Fab")
		)
		(fp_line
			(start -0.1016 0.2794)
			(end -0.1016 0.3048)
			(stroke
				(width 0.1)
				(type default)
			)
			(layer "F.Fab")
		)
		(fp_line
			(start 0.1016 0.2794)
			(end -0.1016 0.2794)
			(stroke
				(width 0.1)
				(type default)
			)
			(layer "F.Fab")
		)
		(fp_line
			(start -0.1016 -0.2794)
			(end 0.1016 -0.2794)
			(stroke
				(width 0.1)
				(type default)
			)
			(layer "F.Fab")
		)
		(fp_line
			(start 0.1016 -0.2794)
			(end 0.1016 -0.3048)
			(stroke
				(width 0.1)
				(type default)
			)
			(layer "F.Fab")
		)
		(fp_line
			(start -0.6858 -0.3048)
			(end -0.1016 -0.3048)
			(stroke
				(width 0.1)
				(type default)
			)
			(layer "F.Fab")
		)
		(fp_line
			(start -0.1016 -0.3048)
			(end -0.1016 -0.2794)
			(stroke
				(width 0.1)
				(type default)
			)
			(layer "F.Fab")
		)
		(fp_line
			(start 0.1016 -0.3048)
			(end 0.6858 -0.3048)
			(stroke
				(width 0.1)
				(type default)
			)
			(layer "F.Fab")
		)
		(fp_line
			(start 0.6858 -0.3048)
			(end 0.6858 0.3048)
			(stroke
				(width 0.1)
				(type default)
			)
			(layer "F.Fab")
		)
		(pad "1" smd rect
			(at -0.40005 0 90)
			(size 0.4572 0.508)
			(layers "F.Cu" "F.Mask" "F.Paste")
			(net "USB3_CPU0_BMC_RX_HUB1_DN")
		)
		(pad "2" smd rect
			(at 0.40005 0 90)
			(size 0.4572 0.508)
			(layers "F.Cu" "F.Mask" "F.Paste")
			(net "USB3_CPU0_BMC_RX_HUB_C_DN")
		)
	)
	(footprint ""
		(layer "F.Cu")
		(at 93.996256 -61.248544 90)
		(property "Reference" "PR3829"
			(at 0 0 90)
			(layer "F.SilkS")
			(hide yes)
			(effects
				(font
					(size 1.27 1.27)
				)
			)
		)
		(property "Value" ""
			(at 0 0 90)
			(layer "F.Fab")
			(effects
				(font
					(size 1.27 1.27)
				)
			)
		)
		(duplicate_pad_numbers_are_jumpers no)
		(fp_line
			(start 0.7874 -0.4064)
			(end 0.7874 0.4064)
			(stroke
				(width 0.1524)
				(type default)
			)
			(layer "F.SilkS")
		)
		(fp_line
			(start -0.7874 -0.4064)
			(end 0.7874 -0.4064)
			(stroke
				(width 0.1524)
				(type default)
			)
			(layer "F.SilkS")
		)
		(fp_line
			(start 0.7874 0.4064)
			(end -0.7874 0.4064)
			(stroke
				(width 0.1524)
				(type default)
			)
			(layer "F.SilkS")
		)
		(fp_line
			(start -0.7874 0.4064)
			(end -0.7874 -0.4064)
			(stroke
				(width 0.1524)
				(type default)
			)
			(layer "F.SilkS")
		)
		(fp_line
			(start -0.12065 -0.305054)
			(end -0.12065 -0.2794)
			(stroke
				(width 0.1)
				(type default)
			)
			(layer "F.Fab")
		)
		(fp_line
			(start -0.67945 -0.305054)
			(end -0.12065 -0.305054)
			(stroke
				(width 0.1)
				(type default)
			)
			(layer "F.Fab")
		)
		(fp_line
			(start 0.67945 -0.3048)
			(end 0.67945 0.3048)
			(stroke
				(width 0.1)
				(type default)
			)
			(layer "F.Fab")
		)
		(fp_line
			(start 0.12065 -0.3048)
			(end 0.67945 -0.3048)
			(stroke
				(width 0.1)
				(type default)
			)
			(layer "F.Fab")
		)
		(fp_line
			(start 0.12065 -0.2794)
			(end 0.12065 -0.3048)
			(stroke
				(width 0.1)
				(type default)
			)
			(layer "F.Fab")
		)
		(fp_line
			(start -0.12065 -0.2794)
			(end 0.12065 -0.2794)
			(stroke
				(width 0.1)
				(type default)
			)
			(layer "F.Fab")
		)
		(fp_line
			(start 0.120396 0.2794)
			(end -0.12065 0.2794)
			(stroke
				(width 0.1)
				(type default)
			)
			(layer "F.Fab")
		)
		(fp_line
			(start -0.12065 0.2794)
			(end -0.12065 0.3048)
			(stroke
				(width 0.1)
				(type default)
			)
			(layer "F.Fab")
		)
		(fp_line
			(start 0.67945 0.3048)
			(end 0.120396 0.3048)
			(stroke
				(width 0.1)
				(type default)
			)
			(layer "F.Fab")
		)
		(fp_line
			(start 0.120396 0.3048)
			(end 0.120396 0.2794)
			(stroke
				(width 0.1)
				(type default)
			)
			(layer "F.Fab")
		)
		(fp_line
			(start -0.12065 0.3048)
			(end -0.67945 0.3048)
			(stroke
				(width 0.1)
				(type default)
			)
			(layer "F.Fab")
		)
		(fp_line
			(start -0.67945 0.3048)
			(end -0.67945 -0.305054)
			(stroke
				(width 0.1)
				(type default)
			)
			(layer "F.Fab")
		)
		(pad "1" smd circle
			(at -0.40005 0 90)
			(size 0 0)
			(layers "F.Cu" "F.Mask" "F.Paste")
			(net "P3V3_OCP_UV_2")
		)
		(pad "2" smd circle
			(at 0.40005 0 90)
			(size 0 0)
			(layers "F.Cu" "F.Mask" "F.Paste")
			(net "P3V3_OCP_OV_2")
		)
	)
)
